(kicad_pcb
	(version 20260206)
	(generator "pcbnew")
	(generator_version "10.0")
	(general
		(thickness 1.6)
		(legacy_teardrops no)
	)
	(paper "A4")
	(title_block
		(title "Wiwynn_Tioga_Pass_MB.brd")
		(comment 1 "Tioga Pass / footprints 3864-3871 of 4770")
	)
	(layers
		(0 "F.Cu" signal "TOP")
		(4 "In1.Cu" signal "L2GND")
		(6 "In2.Cu" signal "L3")
		(8 "In3.Cu" signal "L4GND")
		(10 "In4.Cu" signal "L5")
		(12 "In5.Cu" signal "L6GND")
		(14 "In6.Cu" signal "L7VCC")
		(16 "In7.Cu" signal "L8VCC")
		(18 "In8.Cu" signal "L9GND")
		(20 "In9.Cu" signal "L10")
		(22 "In10.Cu" signal "L11GND")
		(24 "In11.Cu" signal "L12")
		(26 "In12.Cu" signal "L13GND")
		(2 "B.Cu" signal "BOTTOM")
		(9 "F.Adhes" user "F.Adhesive")
		(11 "B.Adhes" user "B.Adhesive")
		(13 "F.Paste" user "Package Geometry/Pastemask Top")
		(15 "B.Paste" user "Package Geometry/Pastemask Bottom")
		(5 "F.SilkS" user "Ref Des/Silkscreen Top")
		(7 "B.SilkS" user "Ref Des/Silkscreen Bottom")
		(1 "F.Mask" user "Board Geometry/Soldermask Top")
		(3 "B.Mask" user "Board Geometry/Soldermask Bottom")
		(17 "Dwgs.User" user "User.Drawings")
		(19 "Cmts.User" user "User.Comments")
		(21 "Eco1.User" user "User.Eco1")
		(23 "Eco2.User" user "User.Eco2")
		(25 "Edge.Cuts" user "Board Geometry/Outline")
		(27 "Margin" user)
		(31 "F.CrtYd" user "Package Geometry/Place Bound Top")
		(29 "B.CrtYd" user "Package Geometry/Place Bound Bottom")
		(35 "F.Fab" user "Ref Des/Assembly Top")
		(33 "B.Fab" user "Ref Des/Assembly Bottom")
	)
	(footprint ""
		(layer "B.Cu")
		(at 474.41866 -29.96692 90)
		(property "Reference" "C2T27"
			(at 0 0 90)
			(layer "B.SilkS")
			(hide yes)
			(effects
				(font
					(size 1.27 1.27)
				)
				(justify mirror)
			)
		)
		(property "Value" ""
			(at 0 0 90)
			(layer "B.Fab")
			(effects
				(font
					(size 1.27 1.27)
				)
				(justify mirror)
			)
		)
		(duplicate_pad_numbers_are_jumpers no)
		(fp_poly
			(pts
				(xy -0.3048 -0.1016) (xy -0.3048 0.9906) (xy 0.3048 0.9906) (xy 0.3048 -0.1016)
			)
			(stroke
				(width 0)
				(type default)
			)
			(fill no)
			(layer "B.CrtYd")
		)
		(fp_line
			(start 0.3048 -0.1016)
			(end 0.3048 0.9906)
			(stroke
				(width 0.1)
				(type default)
			)
			(layer "B.Fab")
		)
		(fp_line
			(start -0.3048 -0.1016)
			(end 0.3048 -0.1016)
			(stroke
				(width 0.1)
				(type default)
			)
			(layer "B.Fab")
		)
		(fp_line
			(start 0.3048 0.9906)
			(end -0.3048 0.9906)
			(stroke
				(width 0.1)
				(type default)
			)
			(layer "B.Fab")
		)
		(fp_line
			(start -0.3048 0.9906)
			(end -0.3048 -0.1016)
			(stroke
				(width 0.1)
				(type default)
			)
			(layer "B.Fab")
		)
		(pad "1" smd rect
			(at 0 0 270)
			(size 0.508 0.508)
			(layers "B.Cu" "B.Mask" "B.Paste")
			(net "P3V3_STBY_MNG_RGMII")
		)
		(pad "2" smd rect
			(at 0 0.889 270)
			(size 0.508 0.508)
			(layers "B.Cu" "B.Mask" "B.Paste")
			(net "GND")
		)
		(zone
			(layer "B.Cu")
			(hatch none 0.5)
			(connect_pads
				(clearance 0)
			)
			(min_thickness 0.25)
			(keepout
				(tracks allowed)
				(vias not_allowed)
				(pads allowed)
				(copperpour not_allowed)
				(footprints allowed)
			)
			(placement
				(enabled no)
				(sheetname "")
			)
			(fill
				(thermal_gap 0.5)
				(thermal_bridge_width 0.5)
				(island_removal_mode 0)
			)
			(polygon
				(pts
					(xy 474.67266 -30.22092) (xy 474.67266 -29.71292) (xy 475.05366 -29.71292) (xy 475.05366 -30.22092)
				)
			)
		)
		(zone
			(layer "B.Cu")
			(hatch none 0.5)
			(connect_pads
				(clearance 0)
			)
			(min_thickness 0.25)
			(keepout
				(tracks not_allowed)
				(vias allowed)
				(pads allowed)
				(copperpour not_allowed)
				(footprints allowed)
			)
			(placement
				(enabled no)
				(sheetname "")
			)
			(fill
				(thermal_gap 0.5)
				(thermal_bridge_width 0.5)
				(island_removal_mode 0)
			)
			(polygon
				(pts
					(xy 475.05366 -30.22092) (xy 475.05366 -29.71292) (xy 474.67266 -29.71292) (xy 474.67266 -30.22092)
				)
			)
		)
	)
	(footprint ""
		(layer "B.Cu")
		(at 276.487128 -156.960824 90)
		(property "Reference" "C5L1"
			(at 0 0 90)
			(layer "B.SilkS")
			(hide yes)
			(effects
				(font
					(size 1.27 1.27)
				)
				(justify mirror)
			)
		)
		(property "Value" ""
			(at 0 0 90)
			(layer "B.Fab")
			(effects
				(font
					(size 1.27 1.27)
				)
				(justify mirror)
			)
		)
		(duplicate_pad_numbers_are_jumpers no)
		(fp_rect
			(start 0.7239 1.9939)
			(end -0.7239 -0.2159)
			(stroke
				(width 0)
				(type default)
			)
			(fill no)
			(layer "B.CrtYd")
		)
		(fp_line
			(start 0.7239 -0.2159)
			(end 0.7239 1.9939)
			(stroke
				(width 0.1)
				(type default)
			)
			(layer "B.Fab")
		)
		(fp_line
			(start -0.7239 -0.2159)
			(end 0.7239 -0.2159)
			(stroke
				(width 0.1)
				(type default)
			)
			(layer "B.Fab")
		)
		(fp_line
			(start 0.7239 1.9939)
			(end -0.7239 1.9939)
			(stroke
				(width 0.1)
				(type default)
			)
			(layer "B.Fab")
		)
		(fp_line
			(start -0.7239 1.9939)
			(end -0.7239 -0.2159)
			(stroke
				(width 0.1)
				(type default)
			)
			(layer "B.Fab")
		)
		(pad "1" smd rect
			(at 0 0 270)
			(size 1.27 1.016)
			(layers "B.Cu" "B.Mask" "B.Paste")
			(net "PVDDQ_DEF")
		)
		(pad "2" smd rect
			(at 0 1.778 270)
			(size 1.27 1.016)
			(layers "B.Cu" "B.Mask" "B.Paste")
			(net "GND")
		)
		(zone
			(layer "B.Cu")
			(hatch none 0.5)
			(connect_pads
				(clearance 0)
			)
			(min_thickness 0.25)
			(keepout
				(tracks not_allowed)
				(vias allowed)
				(pads allowed)
				(copperpour not_allowed)
				(footprints allowed)
			)
			(placement
				(enabled no)
				(sheetname "")
			)
			(fill
				(thermal_gap 0.5)
				(thermal_bridge_width 0.5)
				(island_removal_mode 0)
			)
			(polygon
				(pts
					(xy 277.757128 -157.595824) (xy 276.995128 -157.595824) (xy 276.995128 -156.325824) (xy 277.757128 -156.325824)
				)
			)
		)
	)
	(footprint ""
		(layer "B.Cu")
		(at 404.0124 -105.8545 180)
		(property "Reference" "C2N17"
			(at 0 0 0)
			(layer "B.SilkS")
			(hide yes)
			(effects
				(font
					(size 1.27 1.27)
				)
				(justify mirror)
			)
		)
		(property "Value" ""
			(at 0 0 0)
			(layer "B.Fab")
			(effects
				(font
					(size 1.27 1.27)
				)
				(justify mirror)
			)
		)
		(duplicate_pad_numbers_are_jumpers no)
		(fp_poly
			(pts
				(xy 0.4953 -0.2032) (xy -0.4953 -0.2032) (xy -0.4953 1.6002) (xy 0.4953 1.6002)
			)
			(stroke
				(width 0)
				(type default)
			)
			(fill no)
			(layer "B.CrtYd")
		)
		(fp_line
			(start 0.4953 1.6002)
			(end 0.4953 -0.2032)
			(stroke
				(width 0.1)
				(type default)
			)
			(layer "B.Fab")
		)
		(fp_line
			(start 0.4953 -0.2032)
			(end -0.4953 -0.2032)
			(stroke
				(width 0.1)
				(type default)
			)
			(layer "B.Fab")
		)
		(fp_line
			(start -0.4953 1.6002)
			(end 0.4953 1.6002)
			(stroke
				(width 0.1)
				(type default)
			)
			(layer "B.Fab")
		)
		(fp_line
			(start -0.4953 -0.2032)
			(end -0.4953 1.6002)
			(stroke
				(width 0.1)
				(type default)
			)
			(layer "B.Fab")
		)
		(pad "1" smd rect
			(at 0 0)
			(size 0.762 0.889)
			(layers "B.Cu" "B.Mask" "B.Paste")
			(net "P3V3_STBY")
		)
		(pad "2" smd rect
			(at 0 1.397)
			(size 0.762 0.889)
			(layers "B.Cu" "B.Mask" "B.Paste")
			(net "GND")
		)
		(zone
			(layer "B.Cu")
			(hatch none 0.5)
			(connect_pads
				(clearance 0)
			)
			(min_thickness 0.25)
			(keepout
				(tracks not_allowed)
				(vias allowed)
				(pads allowed)
				(copperpour not_allowed)
				(footprints allowed)
			)
			(placement
				(enabled no)
				(sheetname "")
			)
			(fill
				(thermal_gap 0.5)
				(thermal_bridge_width 0.5)
				(island_removal_mode 0)
			)
			(polygon
				(pts
					(xy 403.6314 -106.299) (xy 404.3934 -106.299) (xy 404.3934 -106.807) (xy 403.6314 -106.807)
				)
			)
		)
	)
	(footprint ""
		(layer "B.Cu")
		(at 373.6975 -55.88 -90)
		(property "Reference" "R3P41"
			(at 0 0 90)
			(layer "B.SilkS")
			(hide yes)
			(effects
				(font
					(size 1.27 1.27)
				)
				(justify mirror)
			)
		)
		(property "Value" ""
			(at 0 0 90)
			(layer "B.Fab")
			(effects
				(font
					(size 1.27 1.27)
				)
				(justify mirror)
			)
		)
		(duplicate_pad_numbers_are_jumpers no)
		(fp_poly
			(pts
				(xy 0.2794 -0.1016) (xy -0.2794 -0.1016) (xy -0.2794 0.9906) (xy 0.2794 0.9906)
			)
			(stroke
				(width 0)
				(type default)
			)
			(fill no)
			(layer "B.CrtYd")
		)
		(fp_line
			(start -0.2794 0.9906)
			(end -0.2794 -0.1016)
			(stroke
				(width 0.1)
				(type default)
			)
			(layer "B.Fab")
		)
		(fp_line
			(start 0.2794 0.9906)
			(end -0.2794 0.9906)
			(stroke
				(width 0.1)
				(type default)
			)
			(layer "B.Fab")
		)
		(fp_line
			(start -0.2794 -0.1016)
			(end 0.2794 -0.1016)
			(stroke
				(width 0.1)
				(type default)
			)
			(layer "B.Fab")
		)
		(fp_line
			(start 0.2794 -0.1016)
			(end 0.2794 0.9906)
			(stroke
				(width 0.1)
				(type default)
			)
			(layer "B.Fab")
		)
		(pad "1" smd rect
			(at 0 0 90)
			(size 0.508 0.508)
			(layers "B.Cu" "B.Mask" "B.Paste")
			(net "PVCCIO_CPU1")
		)
		(pad "2" smd rect
			(at 0 0.889 90)
			(size 0.508 0.508)
			(layers "B.Cu" "B.Mask" "B.Paste")
			(net "H_CPU1_THERMTRIP_G_N")
		)
		(zone
			(layer "B.Cu")
			(hatch none 0.5)
			(connect_pads
				(clearance 0)
			)
			(min_thickness 0.25)
			(keepout
				(tracks not_allowed)
				(vias allowed)
				(pads allowed)
				(copperpour not_allowed)
				(footprints allowed)
			)
			(placement
				(enabled no)
				(sheetname "")
			)
			(fill
				(thermal_gap 0.5)
				(thermal_bridge_width 0.5)
				(island_removal_mode 0)
			)
			(polygon
				(pts
					(xy 373.0625 -55.626) (xy 373.0625 -56.134) (xy 373.4435 -56.134) (xy 373.4435 -55.626)
				)
			)
		)
		(zone
			(layer "B.Cu")
			(hatch none 0.5)
			(connect_pads
				(clearance 0)
			)
			(min_thickness 0.25)
			(keepout
				(tracks allowed)
				(vias not_allowed)
				(pads allowed)
				(copperpour not_allowed)
				(footprints allowed)
			)
			(placement
				(enabled no)
				(sheetname "")
			)
			(fill
				(thermal_gap 0.5)
				(thermal_bridge_width 0.5)
				(island_removal_mode 0)
			)
			(polygon
				(pts
					(xy 373.4435 -55.626) (xy 373.4435 -56.134) (xy 373.0625 -56.134) (xy 373.0625 -55.626)
				)
			)
		)
	)
	(footprint ""
		(layer "B.Cu")
		(at 470.404444 -7.53872 -90)
		(property "Reference" "C2U20"
			(at 0 0 90)
			(layer "B.SilkS")
			(hide yes)
			(effects
				(font
					(size 1.27 1.27)
				)
				(justify mirror)
			)
		)
		(property "Value" ""
			(at 0 0 90)
			(layer "B.Fab")
			(effects
				(font
					(size 1.27 1.27)
				)
				(justify mirror)
			)
		)
		(duplicate_pad_numbers_are_jumpers no)
		(fp_poly
			(pts
				(xy -0.3048 -0.1016) (xy -0.3048 0.9906) (xy 0.3048 0.9906) (xy 0.3048 -0.1016)
			)
			(stroke
				(width 0)
				(type default)
			)
			(fill no)
			(layer "B.CrtYd")
		)
		(fp_line
			(start -0.3048 0.9906)
			(end -0.3048 -0.1016)
			(stroke
				(width 0.1)
				(type default)
			)
			(layer "B.Fab")
		)
		(fp_line
			(start 0.3048 0.9906)
			(end -0.3048 0.9906)
			(stroke
				(width 0.1)
				(type default)
			)
			(layer "B.Fab")
		)
		(fp_line
			(start -0.3048 -0.1016)
			(end 0.3048 -0.1016)
			(stroke
				(width 0.1)
				(type default)
			)
			(layer "B.Fab")
		)
		(fp_line
			(start 0.3048 -0.1016)
			(end 0.3048 0.9906)
			(stroke
				(width 0.1)
				(type default)
			)
			(layer "B.Fab")
		)
		(pad "1" smd rect
			(at 0 0 90)
			(size 0.508 0.508)
			(layers "B.Cu" "B.Mask" "B.Paste")
			(net "P12V")
		)
		(pad "2" smd rect
			(at 0 0.889 90)
			(size 0.508 0.508)
			(layers "B.Cu" "B.Mask" "B.Paste")
			(net "GND")
		)
		(zone
			(layer "B.Cu")
			(hatch none 0.5)
			(connect_pads
				(clearance 0)
			)
			(min_thickness 0.25)
			(keepout
				(tracks not_allowed)
				(vias allowed)
				(pads allowed)
				(copperpour not_allowed)
				(footprints allowed)
			)
			(placement
				(enabled no)
				(sheetname "")
			)
			(fill
				(thermal_gap 0.5)
				(thermal_bridge_width 0.5)
				(island_removal_mode 0)
			)
			(polygon
				(pts
					(xy 469.769444 -7.28472) (xy 469.769444 -7.79272) (xy 470.150444 -7.79272) (xy 470.150444 -7.28472)
				)
			)
		)
		(zone
			(layer "B.Cu")
			(hatch none 0.5)
			(connect_pads
				(clearance 0)
			)
			(min_thickness 0.25)
			(keepout
				(tracks allowed)
				(vias not_allowed)
				(pads allowed)
				(copperpour not_allowed)
				(footprints allowed)
			)
			(placement
				(enabled no)
				(sheetname "")
			)
			(fill
				(thermal_gap 0.5)
				(thermal_bridge_width 0.5)
				(island_removal_mode 0)
			)
			(polygon
				(pts
					(xy 470.150444 -7.28472) (xy 470.150444 -7.79272) (xy 469.769444 -7.79272) (xy 469.769444 -7.28472)
				)
			)
		)
	)
	(footprint ""
		(layer "B.Cu")
		(at 103.333296 -156.910024 -90)
		(property "Reference" "C8L2"
			(at 0 0 90)
			(layer "B.SilkS")
			(hide yes)
			(effects
				(font
					(size 1.27 1.27)
				)
				(justify mirror)
			)
		)
		(property "Value" ""
			(at 0 0 90)
			(layer "B.Fab")
			(effects
				(font
					(size 1.27 1.27)
				)
				(justify mirror)
			)
		)
		(duplicate_pad_numbers_are_jumpers no)
		(fp_poly
			(pts
				(xy 0.7239 -0.2159) (xy -0.7239 -0.2159) (xy -0.7239 1.9939) (xy 0.7239 1.9939)
			)
			(stroke
				(width 0)
				(type default)
			)
			(fill no)
			(layer "B.CrtYd")
		)
		(fp_line
			(start -0.7239 1.9939)
			(end -0.7239 -0.2159)
			(stroke
				(width 0.1)
				(type default)
			)
			(layer "B.Fab")
		)
		(fp_line
			(start 0.7239 1.9939)
			(end -0.7239 1.9939)
			(stroke
				(width 0.1)
				(type default)
			)
			(layer "B.Fab")
		)
		(fp_line
			(start -0.7239 -0.2159)
			(end 0.7239 -0.2159)
			(stroke
				(width 0.1)
				(type default)
			)
			(layer "B.Fab")
		)
		(fp_line
			(start 0.7239 -0.2159)
			(end 0.7239 1.9939)
			(stroke
				(width 0.1)
				(type default)
			)
			(layer "B.Fab")
		)
		(pad "1" smd rect
			(at 0 0 90)
			(size 1.27 1.016)
			(layers "B.Cu" "B.Mask" "B.Paste")
			(net "PVDDQ_KLM")
		)
		(pad "2" smd rect
			(at 0 1.778 90)
			(size 1.27 1.016)
			(layers "B.Cu" "B.Mask" "B.Paste")
			(net "GND")
		)
		(zone
			(layer "B.Cu")
			(hatch none 0.5)
			(connect_pads
				(clearance 0)
			)
			(min_thickness 0.25)
			(keepout
				(tracks not_allowed)
				(vias allowed)
				(pads allowed)
				(copperpour not_allowed)
				(footprints allowed)
			)
			(placement
				(enabled no)
				(sheetname "")
			)
			(fill
				(thermal_gap 0.5)
				(thermal_bridge_width 0.5)
				(island_removal_mode 0)
			)
			(polygon
				(pts
					(xy 102.825296 -156.275024) (xy 102.825296 -157.545024) (xy 102.063296 -157.545024) (xy 102.063296 -156.275024)
				)
			)
		)
	)
	(footprint ""
		(layer "B.Cu")
		(at 400.667474 -22.221698 180)
		(property "Reference" "R1U26"
			(at 0 0 0)
			(layer "B.SilkS")
			(hide yes)
			(effects
				(font
					(size 1.27 1.27)
				)
				(justify mirror)
			)
		)
		(property "Value" ""
			(at 0 0 0)
			(layer "B.Fab")
			(effects
				(font
					(size 1.27 1.27)
				)
				(justify mirror)
			)
		)
		(duplicate_pad_numbers_are_jumpers no)
		(fp_poly
			(pts
				(xy 0.2794 -0.1016) (xy -0.2794 -0.1016) (xy -0.2794 0.9906) (xy 0.2794 0.9906)
			)
			(stroke
				(width 0)
				(type default)
			)
			(fill no)
			(layer "B.CrtYd")
		)
		(fp_line
			(start 0.2794 0.9906)
			(end -0.2794 0.9906)
			(stroke
				(width 0.1)
				(type default)
			)
			(layer "B.Fab")
		)
		(fp_line
			(start 0.2794 -0.1016)
			(end 0.2794 0.9906)
			(stroke
				(width 0.1)
				(type default)
			)
			(layer "B.Fab")
		)
		(fp_line
			(start -0.2794 0.9906)
			(end -0.2794 -0.1016)
			(stroke
				(width 0.1)
				(type default)
			)
			(layer "B.Fab")
		)
		(fp_line
			(start -0.2794 -0.1016)
			(end 0.2794 -0.1016)
			(stroke
				(width 0.1)
				(type default)
			)
			(layer "B.Fab")
		)
		(pad "1" smd rect
			(at 0 0)
			(size 0.508 0.508)
			(layers "B.Cu" "B.Mask" "B.Paste")
			(net "P3V3")
		)
		(pad "2" smd rect
			(at 0 0.889)
			(size 0.508 0.508)
			(layers "B.Cu" "B.Mask" "B.Paste")
			(net "A_P3V3_SCALED")
		)
		(zone
			(layer "B.Cu")
			(hatch none 0.5)
			(connect_pads
				(clearance 0)
			)
			(min_thickness 0.25)
			(keepout
				(tracks not_allowed)
				(vias allowed)
				(pads allowed)
				(copperpour not_allowed)
				(footprints allowed)
			)
			(placement
				(enabled no)
				(sheetname "")
			)
			(fill
				(thermal_gap 0.5)
				(thermal_bridge_width 0.5)
				(island_removal_mode 0)
			)
			(polygon
				(pts
					(xy 400.413474 -22.856698) (xy 400.921474 -22.856698) (xy 400.921474 -22.475698) (xy 400.413474 -22.475698)
				)
			)
		)
		(zone
			(layer "B.Cu")
			(hatch none 0.5)
			(connect_pads
				(clearance 0)
			)
			(min_thickness 0.25)
			(keepout
				(tracks allowed)
				(vias not_allowed)
				(pads allowed)
				(copperpour not_allowed)
				(footprints allowed)
			)
			(placement
				(enabled no)
				(sheetname "")
			)
			(fill
				(thermal_gap 0.5)
				(thermal_bridge_width 0.5)
				(island_removal_mode 0)
			)
			(polygon
				(pts
					(xy 400.413474 -22.475698) (xy 400.921474 -22.475698) (xy 400.921474 -22.856698) (xy 400.413474 -22.856698)
				)
			)
		)
	)
	(footprint ""
		(layer "B.Cu")
		(at 500.3292 -146.8374)
		(property "Reference" "R6W39"
			(at 0.8382 -0.67818 0)
			(unlocked yes)
			(layer "B.SilkS")
			(effects
				(font
					(size 0.4064 0.254)
					(thickness 0.1524)
				)
				(justify left mirror)
			)
		)
		(property "Value" ""
			(at 0 0 0)
			(layer "B.Fab")
			(effects
				(font
					(size 1.27 1.27)
				)
				(justify mirror)
			)
		)
		(duplicate_pad_numbers_are_jumpers no)
		(fp_poly
			(pts
				(xy 0.2794 -0.1016) (xy -0.2794 -0.1016) (xy -0.2794 0.9906) (xy 0.2794 0.9906)
			)
			(stroke
				(width 0)
				(type default)
			)
			(fill no)
			(layer "B.CrtYd")
		)
		(fp_line
			(start -0.2794 -0.1016)
			(end 0.2794 -0.1016)
			(stroke
				(width 0.1)
				(type default)
			)
			(layer "B.Fab")
		)
		(fp_line
			(start -0.2794 0.9906)
			(end -0.2794 -0.1016)
			(stroke
				(width 0.1)
				(type default)
			)
			(layer "B.Fab")
		)
		(fp_line
			(start 0.2794 -0.1016)
			(end 0.2794 0.9906)
			(stroke
				(width 0.1)
				(type default)
			)
			(layer "B.Fab")
		)
		(fp_line
			(start 0.2794 0.9906)
			(end -0.2794 0.9906)
			(stroke
				(width 0.1)
				(type default)
			)
			(layer "B.Fab")
		)
		(pad "1" smd rect
			(at 0 0 180)
			(size 0.508 0.508)
			(layers "B.Cu" "B.Mask" "B.Paste")
			(net "SPA_MID_DBG1_TX_EN")
		)
		(pad "2" smd rect
			(at 0 0.889 180)
			(size 0.508 0.508)
			(layers "B.Cu" "B.Mask" "B.Paste")
			(net "P3V3_STBY")
		)
		(zone
			(layer "B.Cu")
			(hatch none 0.5)
			(connect_pads
				(clearance 0)
			)
			(min_thickness 0.25)
			(keepout
				(tracks allowed)
				(vias not_allowed)
				(pads allowed)
				(copperpour not_allowed)
				(footprints allowed)
			)
			(placement
				(enabled no)
				(sheetname "")
			)
			(fill
				(thermal_gap 0.5)
				(thermal_bridge_width 0.5)
				(island_removal_mode 0)
			)
			(polygon
				(pts
					(xy 500.5832 -146.5834) (xy 500.0752 -146.5834) (xy 500.0752 -146.2024) (xy 500.5832 -146.2024)
				)
			)
		)
		(zone
			(layer "B.Cu")
			(hatch none 0.5)
			(connect_pads
				(clearance 0)
			)
			(min_thickness 0.25)
			(keepout
				(tracks not_allowed)
				(vias allowed)
				(pads allowed)
				(copperpour not_allowed)
				(footprints allowed)
			)
			(placement
				(enabled no)
				(sheetname "")
			)
			(fill
				(thermal_gap 0.5)
				(thermal_bridge_width 0.5)
				(island_removal_mode 0)
			)
			(polygon
				(pts
					(xy 500.5832 -146.2024) (xy 500.0752 -146.2024) (xy 500.0752 -146.5834) (xy 500.5832 -146.5834)
				)
			)
		)
	)
)
